(kicad_pcb
	(version 20260206)
	(generator "pcbnew")
	(generator_version "10.0")
	(general
		(thickness 1.6)
		(legacy_teardrops no)
	)
	(paper "A4")
	(title_block
		(title "04192023_DAF0TMB3IC0_F0TG_MB_C_brd_V02_OCP.brd")
		(comment 1 "Grand Teton / footprint 2783 of 8354 (U26), pads 5889-6000 of 6102")
	)
	(layers
		(0 "F.Cu" signal "TOP")
		(4 "In1.Cu" signal "GND")
		(6 "In2.Cu" signal "IN1")
		(8 "In3.Cu" signal "GND1")
		(10 "In4.Cu" signal "IN2")
		(12 "In5.Cu" signal "GND2")
		(14 "In6.Cu" signal "IN3")
		(16 "In7.Cu" signal "GND3")
		(18 "In8.Cu" signal "VCC")
		(20 "In9.Cu" signal "VCC1")
		(22 "In10.Cu" signal "GND4")
		(24 "In11.Cu" signal "IN4")
		(26 "In12.Cu" signal "GND5")
		(28 "In13.Cu" signal "IN5")
		(30 "In14.Cu" signal "GND6")
		(32 "In15.Cu" signal "IN6")
		(34 "In16.Cu" signal "GND7")
		(2 "B.Cu" signal "BOTTOM")
		(9 "F.Adhes" user "F.Adhesive")
		(11 "B.Adhes" user "B.Adhesive")
		(13 "F.Paste" user "Package Geometry/Pastemask Top")
		(15 "B.Paste" user "Package Geometry/Pastemask Bottom")
		(5 "F.SilkS" user "Ref Des/Silkscreen Top")
		(7 "B.SilkS" user "Ref Des/Silkscreen Bottom")
		(1 "F.Mask" user "Board Geometry/Soldermask Top")
		(3 "B.Mask" user "Board Geometry/Soldermask Bottom")
		(17 "Dwgs.User" user "User.Drawings")
		(19 "Cmts.User" user "User.Comments")
		(21 "Eco1.User" user "User.Eco1")
		(23 "Eco2.User" user "User.Eco2")
		(25 "Edge.Cuts" user "Board Geometry/Outline")
		(27 "Margin" user)
		(31 "F.CrtYd" user "Package Geometry/Place Bound Top")
		(29 "B.CrtYd" user "Package Geometry/Place Bound Bottom")
		(35 "F.Fab" user "Ref Des/Assembly Top")
		(33 "B.Fab" user "Ref Des/Assembly Bottom")
	)
	(footprint ""
		(layer "F.Cu")
		(at 111.927894 -258.880356 180)
		(property "Reference" "U26"
			(at -45.05579 -61.794136 0)
			(unlocked yes)
			(layer "F.SilkS")
			(effects
				(font
					(size 0.7874 0.5842)
					(thickness 0.1524)
				)
			)
		)
		(property "Value" ""
			(at 0 0 180)
			(layer "F.Fab")
			(effects
				(font
					(size 1.27 1.27)
				)
			)
		)
		(duplicate_pad_numbers_are_jumpers no)
		(pad "V4" smd circle
			(at -31.809944 -23.040086 180)
			(size 0.450088 0.450088)
			(layers "F.Cu" "F.Mask" "F.Paste")
			(net "M_G_CPU1_SA_DQ<17>")
		)
		(pad "V5" smd circle
			(at -30.86989 -23.040086 180)
			(size 0.450088 0.450088)
			(layers "F.Cu" "F.Mask" "F.Paste")
			(net "GND")
		)
		(pad "V6" smd circle
			(at -29.93009 -23.040086 180)
			(size 0.450088 0.450088)
			(layers "F.Cu" "F.Mask" "F.Paste")
			(net "M_K_CPU1_SA_DQ<18>")
		)
		(pad "V7" smd circle
			(at -28.990036 -23.040086 180)
			(size 0.450088 0.450088)
			(layers "F.Cu" "F.Mask" "F.Paste")
			(net "M_K_CPU1_SA_DQ<17>")
		)
		(pad "V8" smd circle
			(at -28.049982 -23.040086 180)
			(size 0.450088 0.450088)
			(layers "F.Cu" "F.Mask" "F.Paste")
			(net "GND")
		)
		(pad "V9" smd circle
			(at -27.109928 -23.040086 180)
			(size 0.450088 0.450088)
			(layers "F.Cu" "F.Mask" "F.Paste")
			(net "M_L_CPU1_SA_DQ<18>")
		)
		(pad "V10" smd circle
			(at -26.170128 -23.040086 180)
			(size 0.450088 0.450088)
			(layers "F.Cu" "F.Mask" "F.Paste")
			(net "GND")
		)
		(pad "V11" smd circle
			(at -25.230074 -23.040086 180)
			(size 0.450088 0.450088)
			(layers "F.Cu" "F.Mask" "F.Paste")
			(net "M_L_CPU1_SA_DQ<17>")
		)
		(pad "V12" smd circle
			(at -24.29002 -23.040086 180)
			(size 0.450088 0.450088)
			(layers "F.Cu" "F.Mask" "F.Paste")
			(net "GND")
		)
		(pad "V13" smd circle
			(at -23.349966 -23.040086 180)
			(size 0.450088 0.450088)
			(layers "F.Cu" "F.Mask" "F.Paste")
			(net "M_H_CPU1_SA_DQ<18>")
		)
		(pad "V14" smd circle
			(at -22.409912 -23.040086 180)
			(size 0.450088 0.450088)
			(layers "F.Cu" "F.Mask" "F.Paste")
			(net "M_H_CPU1_SA_DQ<17>")
		)
		(pad "V15" smd circle
			(at -21.470112 -23.040086 180)
			(size 0.450088 0.450088)
			(layers "F.Cu" "F.Mask" "F.Paste")
			(net "GND")
		)
		(pad "V16" smd circle
			(at -20.530058 -23.040086 180)
			(size 0.450088 0.450088)
			(layers "F.Cu" "F.Mask" "F.Paste")
			(net "M_J_CPU1_SA_DQ<18>")
		)
		(pad "V17" smd circle
			(at -19.590004 -23.040086 180)
			(size 0.450088 0.450088)
			(layers "F.Cu" "F.Mask" "F.Paste")
			(net "GND")
		)
		(pad "V18" smd circle
			(at -18.64995 -23.040086 180)
			(size 0.450088 0.450088)
			(layers "F.Cu" "F.Mask" "F.Paste")
			(net "M_J_CPU1_SA_DQ<17>")
		)
		(pad "V19" smd circle
			(at -17.709896 -23.040086 180)
			(size 0.450088 0.450088)
			(layers "F.Cu" "F.Mask" "F.Paste")
			(net "GND")
		)
		(pad "V20" smd circle
			(at -16.770096 -23.040086 180)
			(size 0.450088 0.450088)
			(layers "F.Cu" "F.Mask" "F.Paste")
			(net "M_I_CPU1_SA_DQ<18>")
		)
		(pad "V21" smd circle
			(at -15.830042 -23.040086 180)
			(size 0.450088 0.450088)
			(layers "F.Cu" "F.Mask" "F.Paste")
			(net "M_I_CPU1_SA_DQ<17>")
		)
		(pad "V22" smd circle
			(at -14.889988 -23.040086 180)
			(size 0.450088 0.450088)
			(layers "F.Cu" "F.Mask" "F.Paste")
			(net "PVDDCR_SOC_P1")
		)
		(pad "V23" smd circle
			(at -13.949934 -23.040086 180)
			(size 0.450088 0.450088)
			(layers "F.Cu" "F.Mask" "F.Paste")
			(net "GND")
		)
		(pad "V24" smd circle
			(at -13.00988 -23.040086 180)
			(size 0.450088 0.450088)
			(layers "F.Cu" "F.Mask" "F.Paste")
			(net "GND")
		)
		(pad "V25" smd circle
			(at -12.07008 -23.040086 180)
			(size 0.450088 0.450088)
			(layers "F.Cu" "F.Mask" "F.Paste")
			(net "GND")
		)
		(pad "V26" smd circle
			(at -11.130026 -23.040086 180)
			(size 0.450088 0.450088)
			(layers "F.Cu" "F.Mask" "F.Paste")
			(net "GND")
		)
		(pad "V27" smd circle
			(at -10.189972 -23.040086 180)
			(size 0.450088 0.450088)
			(layers "F.Cu" "F.Mask" "F.Paste")
			(net "GND")
		)
		(pad "V28" smd circle
			(at -9.249918 -23.040086 180)
			(size 0.450088 0.450088)
			(layers "F.Cu" "F.Mask" "F.Paste")
			(net "GND")
		)
		(pad "V29" smd circle
			(at -8.310118 -23.040086 180)
			(size 0.450088 0.450088)
			(layers "F.Cu" "F.Mask" "F.Paste")
			(net "GND")
		)
		(pad "V30" smd circle
			(at -7.370064 -23.040086 180)
			(size 0.450088 0.450088)
			(layers "F.Cu" "F.Mask" "F.Paste")
			(net "GND")
		)
		(pad "V31" smd circle
			(at -6.43001 -23.040086 180)
			(size 0.450088 0.450088)
			(layers "F.Cu" "F.Mask" "F.Paste")
			(net "GND")
		)
		(pad "V32" smd circle
			(at -5.489956 -23.040086 180)
			(size 0.450088 0.450088)
			(layers "F.Cu" "F.Mask" "F.Paste")
			(net "GND")
		)
		(pad "V33" smd circle
			(at -4.549902 -23.040086 180)
			(size 0.450088 0.450088)
			(layers "F.Cu" "F.Mask" "F.Paste")
			(net "GND")
		)
		(pad "V34" smd circle
			(at -3.610102 -23.040086 180)
			(size 0.450088 0.450088)
			(layers "F.Cu" "F.Mask" "F.Paste")
			(net "GND")
		)
		(pad "V35" smd circle
			(at -2.670048 -23.040086 180)
			(size 0.450088 0.450088)
			(layers "F.Cu" "F.Mask" "F.Paste")
			(net "GMI_CPU1_G3_CPU0_G1_TX_DP<0>")
		)
		(pad "V36" smd circle
			(at -1.729994 -23.040086 180)
			(size 0.450088 0.450088)
			(layers "F.Cu" "F.Mask" "F.Paste")
			(net "GMI_CPU1_G3_CPU0_G1_TX_DN<0>")
		)
		(pad "V37" smd circle
			(at -0.78994 -23.040086 180)
			(size 0.450088 0.450088)
			(layers "F.Cu" "F.Mask" "F.Paste")
			(net "GND")
		)
		(pad "V39" smd circle
			(at 1.089914 -23.040086 180)
			(size 0.450088 0.450088)
			(layers "F.Cu" "F.Mask" "F.Paste")
			(net "GND")
		)
		(pad "V40" smd circle
			(at 2.029968 -23.040086 180)
			(size 0.450088 0.450088)
			(layers "F.Cu" "F.Mask" "F.Paste")
			(net "P5E_CPU1_G1_RX_DN<0>")
		)
		(pad "V41" smd circle
			(at 2.970022 -23.040086 180)
			(size 0.450088 0.450088)
			(layers "F.Cu" "F.Mask" "F.Paste")
			(net "P5E_CPU1_G1_RX_DP<0>")
		)
		(pad "V42" smd circle
			(at 3.910076 -23.040086 180)
			(size 0.450088 0.450088)
			(layers "F.Cu" "F.Mask" "F.Paste")
			(net "GND")
		)
		(pad "V43" smd circle
			(at 4.849876 -23.040086 180)
			(size 0.450088 0.450088)
			(layers "F.Cu" "F.Mask" "F.Paste")
			(net "GND")
		)
		(pad "V44" smd circle
			(at 5.78993 -23.040086 180)
			(size 0.450088 0.450088)
			(layers "F.Cu" "F.Mask" "F.Paste")
			(net "GND")
		)
		(pad "V45" smd circle
			(at 6.729984 -23.040086 180)
			(size 0.450088 0.450088)
			(layers "F.Cu" "F.Mask" "F.Paste")
			(net "GND")
		)
		(pad "V46" smd circle
			(at 7.670038 -23.040086 180)
			(size 0.450088 0.450088)
			(layers "F.Cu" "F.Mask" "F.Paste")
			(net "GND")
		)
		(pad "V47" smd circle
			(at 8.610092 -23.040086 180)
			(size 0.450088 0.450088)
			(layers "F.Cu" "F.Mask" "F.Paste")
			(net "GND")
		)
		(pad "V48" smd circle
			(at 9.549892 -23.040086 180)
			(size 0.450088 0.450088)
			(layers "F.Cu" "F.Mask" "F.Paste")
			(net "GND")
		)
		(pad "V49" smd circle
			(at 10.489946 -23.040086 180)
			(size 0.450088 0.450088)
			(layers "F.Cu" "F.Mask" "F.Paste")
			(net "GND")
		)
		(pad "V50" smd circle
			(at 11.43 -23.040086 180)
			(size 0.450088 0.450088)
			(layers "F.Cu" "F.Mask" "F.Paste")
			(net "GND")
		)
		(pad "V51" smd circle
			(at 12.370054 -23.040086 180)
			(size 0.450088 0.450088)
			(layers "F.Cu" "F.Mask" "F.Paste")
			(net "GND")
		)
		(pad "V52" smd circle
			(at 13.310108 -23.040086 180)
			(size 0.450088 0.450088)
			(layers "F.Cu" "F.Mask" "F.Paste")
			(net "GND")
		)
		(pad "V53" smd circle
			(at 14.249908 -23.040086 180)
			(size 0.450088 0.450088)
			(layers "F.Cu" "F.Mask" "F.Paste")
			(net "GND")
		)
		(pad "V54" smd circle
			(at 15.189962 -23.040086 180)
			(size 0.450088 0.450088)
			(layers "F.Cu" "F.Mask" "F.Paste")
			(net "PVDDIO_P1")
		)
		(pad "V55" smd circle
			(at 16.130016 -23.040086 180)
			(size 0.450088 0.450088)
			(layers "F.Cu" "F.Mask" "F.Paste")
			(net "M_C_CPU1_SA_DQ<17>")
		)
		(pad "V56" smd circle
			(at 17.07007 -23.040086 180)
			(size 0.450088 0.450088)
			(layers "F.Cu" "F.Mask" "F.Paste")
			(net "M_C_CPU1_SA_DQ<18>")
		)
		(pad "V57" smd circle
			(at 18.010124 -23.040086 180)
			(size 0.450088 0.450088)
			(layers "F.Cu" "F.Mask" "F.Paste")
			(net "GND")
		)
		(pad "V58" smd circle
			(at 18.949924 -23.040086 180)
			(size 0.450088 0.450088)
			(layers "F.Cu" "F.Mask" "F.Paste")
			(net "M_D_CPU1_SA_DQ<17>")
		)
		(pad "V59" smd circle
			(at 19.889978 -23.040086 180)
			(size 0.450088 0.450088)
			(layers "F.Cu" "F.Mask" "F.Paste")
			(net "GND")
		)
		(pad "V60" smd circle
			(at 20.830032 -23.040086 180)
			(size 0.450088 0.450088)
			(layers "F.Cu" "F.Mask" "F.Paste")
			(net "M_D_CPU1_SA_DQ<18>")
		)
		(pad "V61" smd circle
			(at 21.770086 -23.040086 180)
			(size 0.450088 0.450088)
			(layers "F.Cu" "F.Mask" "F.Paste")
			(net "GND")
		)
		(pad "V62" smd circle
			(at 22.709886 -23.040086 180)
			(size 0.450088 0.450088)
			(layers "F.Cu" "F.Mask" "F.Paste")
			(net "M_B_CPU1_SA_DQ<17>")
		)
		(pad "V63" smd circle
			(at 23.64994 -23.040086 180)
			(size 0.450088 0.450088)
			(layers "F.Cu" "F.Mask" "F.Paste")
			(net "M_B_CPU1_SA_DQ<18>")
		)
		(pad "V64" smd circle
			(at 24.589994 -23.040086 180)
			(size 0.450088 0.450088)
			(layers "F.Cu" "F.Mask" "F.Paste")
			(net "GND")
		)
		(pad "V65" smd circle
			(at 25.530048 -23.040086 180)
			(size 0.450088 0.450088)
			(layers "F.Cu" "F.Mask" "F.Paste")
			(net "M_F_CPU1_SA_DQ<17>")
		)
		(pad "V66" smd circle
			(at 26.470102 -23.040086 180)
			(size 0.450088 0.450088)
			(layers "F.Cu" "F.Mask" "F.Paste")
			(net "GND")
		)
		(pad "V67" smd circle
			(at 27.409902 -23.040086 180)
			(size 0.450088 0.450088)
			(layers "F.Cu" "F.Mask" "F.Paste")
			(net "M_F_CPU1_SA_DQ<18>")
		)
		(pad "V68" smd circle
			(at 28.349956 -23.040086 180)
			(size 0.450088 0.450088)
			(layers "F.Cu" "F.Mask" "F.Paste")
			(net "GND")
		)
		(pad "V69" smd circle
			(at 29.29001 -23.040086 180)
			(size 0.450088 0.450088)
			(layers "F.Cu" "F.Mask" "F.Paste")
			(net "M_E_CPU1_SA_DQ<17>")
		)
		(pad "V70" smd circle
			(at 30.230064 -23.040086 180)
			(size 0.450088 0.450088)
			(layers "F.Cu" "F.Mask" "F.Paste")
			(net "M_E_CPU1_SA_DQ<18>")
		)
		(pad "V71" smd circle
			(at 31.170118 -23.040086 180)
			(size 0.450088 0.450088)
			(layers "F.Cu" "F.Mask" "F.Paste")
			(net "GND")
		)
		(pad "V72" smd circle
			(at 32.109918 -23.040086 180)
			(size 0.450088 0.450088)
			(layers "F.Cu" "F.Mask" "F.Paste")
			(net "M_A_CPU1_SA_DQ<17>")
		)
		(pad "V73" smd circle
			(at 33.049972 -23.040086 180)
			(size 0.450088 0.450088)
			(layers "F.Cu" "F.Mask" "F.Paste")
			(net "GND")
		)
		(pad "V74" smd circle
			(at 33.990026 -23.040086 180)
			(size 0.450088 0.450088)
			(layers "F.Cu" "F.Mask" "F.Paste")
			(net "M_A_CPU1_SA_DQ<18>")
		)
		(pad "W1" smd circle
			(at -34.159952 -22.23008 180)
			(size 0.450088 0.450088)
			(layers "F.Cu" "F.Mask" "F.Paste")
			(net "GND")
		)
		(pad "W2" smd circle
			(at -33.219898 -22.23008 180)
			(size 0.450088 0.450088)
			(layers "F.Cu" "F.Mask" "F.Paste")
			(net "M_G_CPU1_SA_DQS_DP<2>")
		)
		(pad "W3" smd circle
			(at -32.280098 -22.23008 180)
			(size 0.450088 0.450088)
			(layers "F.Cu" "F.Mask" "F.Paste")
			(net "M_G_CPU1_SA_DQ<19>")
		)
		(pad "W4" smd circle
			(at -31.340044 -22.23008 180)
			(size 0.450088 0.450088)
			(layers "F.Cu" "F.Mask" "F.Paste")
			(net "GND")
		)
		(pad "W5" smd circle
			(at -30.39999 -22.23008 180)
			(size 0.450088 0.450088)
			(layers "F.Cu" "F.Mask" "F.Paste")
			(net "M_K_CPU1_SA_DQS_DP<2>")
		)
		(pad "W6" smd circle
			(at -29.459936 -22.23008 180)
			(size 0.450088 0.450088)
			(layers "F.Cu" "F.Mask" "F.Paste")
			(net "GND")
		)
		(pad "W7" smd circle
			(at -28.519882 -22.23008 180)
			(size 0.450088 0.450088)
			(layers "F.Cu" "F.Mask" "F.Paste")
			(net "M_K_CPU1_SA_DQ<19>")
		)
		(pad "W8" smd circle
			(at -27.580082 -22.23008 180)
			(size 0.450088 0.450088)
			(layers "F.Cu" "F.Mask" "F.Paste")
			(net "GND")
		)
		(pad "W9" smd circle
			(at -26.640028 -22.23008 180)
			(size 0.450088 0.450088)
			(layers "F.Cu" "F.Mask" "F.Paste")
			(net "M_L_CPU1_SA_DQS_DP<2>")
		)
		(pad "W10" smd circle
			(at -25.699974 -22.23008 180)
			(size 0.450088 0.450088)
			(layers "F.Cu" "F.Mask" "F.Paste")
			(net "M_L_CPU1_SA_DQ<19>")
		)
		(pad "W11" smd circle
			(at -24.75992 -22.23008 180)
			(size 0.450088 0.450088)
			(layers "F.Cu" "F.Mask" "F.Paste")
			(net "GND")
		)
		(pad "W12" smd circle
			(at -23.82012 -22.23008 180)
			(size 0.450088 0.450088)
			(layers "F.Cu" "F.Mask" "F.Paste")
			(net "M_H_CPU1_SA_DQS_DP<2>")
		)
		(pad "W13" smd circle
			(at -22.880066 -22.23008 180)
			(size 0.450088 0.450088)
			(layers "F.Cu" "F.Mask" "F.Paste")
			(net "GND")
		)
		(pad "W14" smd circle
			(at -21.940012 -22.23008 180)
			(size 0.450088 0.450088)
			(layers "F.Cu" "F.Mask" "F.Paste")
			(net "M_H_CPU1_SA_DQ<19>")
		)
		(pad "W15" smd circle
			(at -20.999958 -22.23008 180)
			(size 0.450088 0.450088)
			(layers "F.Cu" "F.Mask" "F.Paste")
			(net "GND")
		)
		(pad "W16" smd circle
			(at -20.059904 -22.23008 180)
			(size 0.450088 0.450088)
			(layers "F.Cu" "F.Mask" "F.Paste")
			(net "M_J_CPU1_SA_DQS_DP<2>")
		)
		(pad "W17" smd circle
			(at -19.120104 -22.23008 180)
			(size 0.450088 0.450088)
			(layers "F.Cu" "F.Mask" "F.Paste")
			(net "M_J_CPU1_SA_DQ<19>")
		)
		(pad "W18" smd circle
			(at -18.18005 -22.23008 180)
			(size 0.450088 0.450088)
			(layers "F.Cu" "F.Mask" "F.Paste")
			(net "GND")
		)
		(pad "W19" smd circle
			(at -17.239996 -22.23008 180)
			(size 0.450088 0.450088)
			(layers "F.Cu" "F.Mask" "F.Paste")
			(net "M_I_CPU1_SA_DQS_DP<2>")
		)
		(pad "W20" smd circle
			(at -16.299942 -22.23008 180)
			(size 0.450088 0.450088)
			(layers "F.Cu" "F.Mask" "F.Paste")
			(net "GND")
		)
		(pad "W21" smd circle
			(at -15.359888 -22.23008 180)
			(size 0.450088 0.450088)
			(layers "F.Cu" "F.Mask" "F.Paste")
			(net "M_I_CPU1_SA_DQ<19>")
		)
		(pad "W22" smd circle
			(at -14.420088 -22.23008 180)
			(size 0.450088 0.450088)
			(layers "F.Cu" "F.Mask" "F.Paste")
			(net "GND")
		)
		(pad "W23" smd circle
			(at -13.480034 -22.23008 180)
			(size 0.450088 0.450088)
			(layers "F.Cu" "F.Mask" "F.Paste")
			(net "GMI_CPU1_G3_CPU0_G1_TX_DP<13>")
		)
		(pad "W24" smd circle
			(at -12.53998 -22.23008 180)
			(size 0.450088 0.450088)
			(layers "F.Cu" "F.Mask" "F.Paste")
			(net "GMI_CPU1_G3_CPU0_G1_TX_DN<13>")
		)
		(pad "W25" smd circle
			(at -11.599926 -22.23008 180)
			(size 0.450088 0.450088)
			(layers "F.Cu" "F.Mask" "F.Paste")
			(net "GND")
		)
		(pad "W26" smd circle
			(at -10.659872 -22.23008 180)
			(size 0.450088 0.450088)
			(layers "F.Cu" "F.Mask" "F.Paste")
			(net "GMI_CPU1_G3_CPU0_G1_TX_DP<9>")
		)
		(pad "W27" smd circle
			(at -9.720072 -22.23008 180)
			(size 0.450088 0.450088)
			(layers "F.Cu" "F.Mask" "F.Paste")
			(net "GMI_CPU1_G3_CPU0_G1_TX_DN<9>")
		)
		(pad "W28" smd circle
			(at -8.780018 -22.23008 180)
			(size 0.450088 0.450088)
			(layers "F.Cu" "F.Mask" "F.Paste")
			(net "GND")
		)
		(pad "W29" smd circle
			(at -7.839964 -22.23008 180)
			(size 0.450088 0.450088)
			(layers "F.Cu" "F.Mask" "F.Paste")
			(net "PVDDCR_CPU0_P1")
		)
		(pad "W30" smd circle
			(at -6.89991 -22.23008 180)
			(size 0.450088 0.450088)
			(layers "F.Cu" "F.Mask" "F.Paste")
			(net "PVDDCR_CPU0_P1")
		)
		(pad "W31" smd circle
			(at -5.96011 -22.23008 180)
			(size 0.450088 0.450088)
			(layers "F.Cu" "F.Mask" "F.Paste")
			(net "TP_CPU1_TEST41_IOD")
		)
		(pad "W32" smd circle
			(at -5.020056 -22.23008 180)
			(size 0.450088 0.450088)
			(layers "F.Cu" "F.Mask" "F.Paste")
			(net "PVDDCR_CPU0_P1")
		)
		(pad "W33" smd circle
			(at -4.080002 -22.23008 180)
			(size 0.450088 0.450088)
			(layers "F.Cu" "F.Mask" "F.Paste")
			(net "PVDDCR_CPU0_P1")
		)
		(pad "W34" smd circle
			(at -3.139948 -22.23008 180)
			(size 0.450088 0.450088)
			(layers "F.Cu" "F.Mask" "F.Paste")
			(net "GND")
		)
		(pad "W35" smd circle
			(at -2.199894 -22.23008 180)
			(size 0.450088 0.450088)
			(layers "F.Cu" "F.Mask" "F.Paste")
			(net "GND")
		)
		(pad "W36" smd circle
			(at -1.260094 -22.23008 180)
			(size 0.450088 0.450088)
			(layers "F.Cu" "F.Mask" "F.Paste")
			(net "GND")
		)
		(pad "W40" smd circle
			(at 1.560068 -22.23008 180)
			(size 0.450088 0.450088)
			(layers "F.Cu" "F.Mask" "F.Paste")
			(net "GND")
		)
		(pad "W41" smd circle
			(at 2.500122 -22.23008 180)
			(size 0.450088 0.450088)
			(layers "F.Cu" "F.Mask" "F.Paste")
			(net "GND")
		)
		(pad "W42" smd circle
			(at 3.439922 -22.23008 180)
			(size 0.450088 0.450088)
			(layers "F.Cu" "F.Mask" "F.Paste")
			(net "GND")
		)
		(pad "W43" smd circle
			(at 4.379976 -22.23008 180)
			(size 0.450088 0.450088)
			(layers "F.Cu" "F.Mask" "F.Paste")
			(net "PVDDCR_CPU0_P1")
		)
		(pad "W44" smd circle
			(at 5.32003 -22.23008 180)
			(size 0.450088 0.450088)
			(layers "F.Cu" "F.Mask" "F.Paste")
			(net "PVDDCR_CPU0_P1")
		)
		(pad "W45" smd circle
			(at 6.260084 -22.23008 180)
			(size 0.450088 0.450088)
			(layers "F.Cu" "F.Mask" "F.Paste")
			(net "GND")
		)
	)
)
